# BASEBOARD_FAB2 (Tioga Pass) — schematic netlist excerpt (pin names and nets, part order shuffled) for the footprints in the layout excerpt that follows; sources: Cadence DE-HDL packaged netlist, KiCad conversion of Wiwynn_Tioga_Pass_MB.brd

R8W1  RES  0.0 5% CHIP  pkg 0402  page 249 : A = BMC_SELF_HW_D_RST ; B = FM_TPM_PRES_RST_N
C5W1  CAP_A  22.0UF 4V 20% X6S  pkg 0603V  page 42 : A = PVCCMCP_CPU0 ; B = GND
Y9E1  CRYSTAL  25.000MHZ IC  pkg 2013  page 139 : A = XTAL_25MHZ_IN ; B = XTAL_25MHZ_OUT_R

(kicad_pcb
	(version 20260206)
	(generator "pcbnew")
	(generator_version "10.0")
	(general
		(thickness 1.6)
		(legacy_teardrops no)
	)
	(paper "A4")
	(title_block
		(title "Wiwynn_Tioga_Pass_MB.brd")
		(comment 1 "Tioga Pass / footprints 1902-1904 of 4770")
	)
	(layers
		(0 "F.Cu" signal "TOP")
		(4 "In1.Cu" signal "L2GND")
		(6 "In2.Cu" signal "L3")
		(8 "In3.Cu" signal "L4GND")
		(10 "In4.Cu" signal "L5")
		(12 "In5.Cu" signal "L6GND")
		(14 "In6.Cu" signal "L7VCC")
		(16 "In7.Cu" signal "L8VCC")
		(18 "In8.Cu" signal "L9GND")
		(20 "In9.Cu" signal "L10")
		(22 "In10.Cu" signal "L11GND")
		(24 "In11.Cu" signal "L12")
		(26 "In12.Cu" signal "L13GND")
		(2 "B.Cu" signal "BOTTOM")
		(9 "F.Adhes" user "F.Adhesive")
		(11 "B.Adhes" user "B.Adhesive")
		(13 "F.Paste" user "Package Geometry/Pastemask Top")
		(15 "B.Paste" user "Package Geometry/Pastemask Bottom")
		(5 "F.SilkS" user "Ref Des/Silkscreen Top")
		(7 "B.SilkS" user "Ref Des/Silkscreen Bottom")
		(1 "F.Mask" user "Board Geometry/Soldermask Top")
		(3 "B.Mask" user "Board Geometry/Soldermask Bottom")
		(17 "Dwgs.User" user "User.Drawings")
		(19 "Cmts.User" user "User.Comments")
		(21 "Eco1.User" user "User.Eco1")
		(23 "Eco2.User" user "User.Eco2")
		(25 "Edge.Cuts" user "Board Geometry/Outline")
		(27 "Margin" user)
		(31 "F.CrtYd" user "Package Geometry/Place Bound Top")
		(29 "B.CrtYd" user "Package Geometry/Place Bound Bottom")
		(35 "F.Fab" user "Ref Des/Assembly Top")
		(33 "B.Fab" user "Ref Des/Assembly Bottom")
	)
	(footprint ""
		(layer "F.Cu")
		(at 474.9927 -40.631364 180)
		(property "Reference" "Y9E1"
			(at 2.77749 0.5842 90)
			(unlocked yes)
			(layer "F.SilkS")
			(effects
				(font
					(size 0.7874 0.5842)
					(thickness 0.1524)
				)
				(justify left)
			)
		)
		(property "Value" ""
			(at 0 0 180)
			(layer "F.Fab")
			(effects
				(font
					(size 1.27 1.27)
				)
			)
		)
		(duplicate_pad_numbers_are_jumpers no)
		(fp_circle
			(center -0.668782 -1.07823)
			(end -0.795782 -1.07823)
			(stroke
				(width 0.254)
				(type default)
			)
			(fill no)
			(layer "F.SilkS")
		)
		(fp_rect
			(start -0.499872 2.70002)
			(end 2.100072 -0.599948)
			(stroke
				(width 0)
				(type default)
			)
			(fill no)
			(layer "F.CrtYd")
		)
		(fp_line
			(start 2.100072 2.70002)
			(end -0.499872 2.70002)
			(stroke
				(width 0.1)
				(type default)
			)
			(layer "F.Fab")
		)
		(fp_line
			(start 2.100072 -0.599948)
			(end 2.100072 2.70002)
			(stroke
				(width 0.1)
				(type default)
			)
			(layer "F.Fab")
		)
		(fp_line
			(start -0.499872 2.70002)
			(end -0.499872 -0.599948)
			(stroke
				(width 0.1)
				(type default)
			)
			(layer "F.Fab")
		)
		(fp_line
			(start -0.499872 -0.599948)
			(end 2.100072 -0.599948)
			(stroke
				(width 0.1)
				(type default)
			)
			(layer "F.Fab")
		)
		(fp_circle
			(center -1.049782 -0.44323)
			(end -1.176782 -0.44323)
			(stroke
				(width 0.254)
				(type default)
			)
			(fill no)
			(layer "F.Fab")
		)
		(pad "1" smd rect
			(at 0 0 180)
			(size 1.0414 1.143)
			(layers "F.Cu" "F.Mask" "F.Paste")
			(net "XTAL_25MHZ_IN")
		)
		(pad "2" smd rect
			(at 0 2.100072 180)
			(size 1.0414 1.143)
			(layers "F.Cu" "F.Mask" "F.Paste")
			(net "GND")
		)
		(pad "3" smd rect
			(at 1.6002 2.100072 180)
			(size 1.0414 1.143)
			(layers "F.Cu" "F.Mask" "F.Paste")
			(net "XTAL_25MHZ_OUT_R")
		)
		(pad "4" smd rect
			(at 1.6002 0 180)
			(size 1.0414 1.143)
			(layers "F.Cu" "F.Mask" "F.Paste")
			(net "GND")
		)
	)
	(footprint ""
		(layer "F.Cu")
		(at 417.8935 -64.897 -90)
		(property "Reference" "R8W1"
			(at -0.8382 -0.67818 270)
			(unlocked yes)
			(layer "F.SilkS")
			(effects
				(font
					(size 0.4064 0.254)
					(thickness 0.1524)
				)
				(justify left)
			)
		)
		(property "Value" ""
			(at 0 0 270)
			(layer "F.Fab")
			(effects
				(font
					(size 1.27 1.27)
				)
			)
		)
		(duplicate_pad_numbers_are_jumpers no)
		(fp_poly
			(pts
				(xy -0.2794 -0.1016) (xy 0.2794 -0.1016) (xy 0.2794 0.9906) (xy -0.2794 0.9906)
			)
			(stroke
				(width 0)
				(type default)
			)
			(fill no)
			(layer "F.CrtYd")
		)
		(fp_line
			(start -0.2794 0.9906)
			(end 0.2794 0.9906)
			(stroke
				(width 0.1)
				(type default)
			)
			(layer "F.Fab")
		)
		(fp_line
			(start 0.2794 0.9906)
			(end 0.2794 -0.1016)
			(stroke
				(width 0.1)
				(type default)
			)
			(layer "F.Fab")
		)
		(fp_line
			(start -0.2794 -0.1016)
			(end -0.2794 0.9906)
			(stroke
				(width 0.1)
				(type default)
			)
			(layer "F.Fab")
		)
		(fp_line
			(start 0.2794 -0.1016)
			(end -0.2794 -0.1016)
			(stroke
				(width 0.1)
				(type default)
			)
			(layer "F.Fab")
		)
		(pad "1" smd rect
			(at 0 0 270)
			(size 0.508 0.508)
			(layers "F.Cu" "F.Mask" "F.Paste")
			(net "BMC_SELF_HW_D_RST")
		)
		(pad "2" smd rect
			(at 0 0.889 270)
			(size 0.508 0.508)
			(layers "F.Cu" "F.Mask" "F.Paste")
			(net "FM_TPM_PRES_RST_N")
		)
		(zone
			(layer "F.Cu")
			(hatch none 0.5)
			(connect_pads
				(clearance 0)
			)
			(min_thickness 0.25)
			(keepout
				(tracks not_allowed)
				(vias allowed)
				(pads allowed)
				(copperpour not_allowed)
				(footprints allowed)
			)
			(placement
				(enabled no)
				(sheetname "")
			)
			(fill
				(thermal_gap 0.5)
				(thermal_bridge_width 0.5)
				(island_removal_mode 0)
			)
			(polygon
				(pts
					(xy 417.2585 -65.151) (xy 417.2585 -64.643) (xy 417.6395 -64.643) (xy 417.6395 -65.151)
				)
			)
		)
		(zone
			(layer "F.Cu")
			(hatch none 0.5)
			(connect_pads
				(clearance 0)
			)
			(min_thickness 0.25)
			(keepout
				(tracks allowed)
				(vias not_allowed)
				(pads allowed)
				(copperpour not_allowed)
				(footprints allowed)
			)
			(placement
				(enabled no)
				(sheetname "")
			)
			(fill
				(thermal_gap 0.5)
				(thermal_bridge_width 0.5)
				(island_removal_mode 0)
			)
			(polygon
				(pts
					(xy 417.6395 -65.151) (xy 417.6395 -64.643) (xy 417.2585 -64.643) (xy 417.2585 -65.151)
				)
			)
		)
	)
	(footprint ""
		(layer "F.Cu")
		(at 269.4432 -79.6036 180)
		(property "Reference" "C5W1"
			(at 0.97536 0.76708 90)
			(unlocked yes)
			(layer "F.SilkS")
			(effects
				(font
					(size 0.4064 0.254)
					(thickness 0.1524)
				)
			)
		)
		(property "Value" ""
			(at 0 0 180)
			(layer "F.Fab")
			(effects
				(font
					(size 1.27 1.27)
				)
			)
		)
		(duplicate_pad_numbers_are_jumpers no)
		(fp_poly
			(pts
				(xy -0.4953 -0.2032) (xy 0.4953 -0.2032) (xy 0.4953 1.6002) (xy -0.4953 1.6002)
			)
			(stroke
				(width 0)
				(type default)
			)
			(fill no)
			(layer "F.CrtYd")
		)
		(fp_line
			(start 0.4953 1.6002)
			(end -0.4953 1.6002)
			(stroke
				(width 0.1)
				(type default)
			)
			(layer "F.Fab")
		)
		(fp_line
			(start 0.4953 -0.2032)
			(end 0.4953 1.6002)
			(stroke
				(width 0.1)
				(type default)
			)
			(layer "F.Fab")
		)
		(fp_line
			(start -0.4953 1.6002)
			(end -0.4953 -0.2032)
			(stroke
				(width 0.1)
				(type default)
			)
			(layer "F.Fab")
		)
		(fp_line
			(start -0.4953 -0.2032)
			(end 0.4953 -0.2032)
			(stroke
				(width 0.1)
				(type default)
			)
			(layer "F.Fab")
		)
		(pad "1" smd rect
			(at 0 0 180)
			(size 0.762 0.889)
			(layers "F.Cu" "F.Mask" "F.Paste")
			(net "PVCCMCP_CPU0")
		)
		(pad "2" smd rect
			(at 0 1.397 180)
			(size 0.762 0.889)
			(layers "F.Cu" "F.Mask" "F.Paste")
			(net "GND")
		)
		(zone
			(layer "F.Cu")
			(hatch none 0.5)
			(connect_pads
				(clearance 0)
			)
			(min_thickness 0.25)
			(keepout
				(tracks not_allowed)
				(vias allowed)
				(pads allowed)
				(copperpour not_allowed)
				(footprints allowed)
			)
			(placement
				(enabled no)
				(sheetname "")
			)
			(fill
				(thermal_gap 0.5)
				(thermal_bridge_width 0.5)
				(island_removal_mode 0)
			)
			(polygon
				(pts
					(xy 269.8242 -80.0481) (xy 269.0622 -80.0481) (xy 269.0622 -80.5561) (xy 269.8242 -80.5561)
				)
			)
		)
	)
)
